# S9S_MB_2U (Grand Teton) — schematic netlist excerpt (pin names and nets, part order shuffled) for the footprints in the layout excerpt that follows; sources: Cadence DE-HDL packaged netlist, KiCad conversion of 03242023_DA0F0TMBIJ0_F0T_Motherboard_J_brd_V01_OCP.brd

R3687  Q_RES  0 5% EMPTY  pkg 0402LF  page 250 : A = P1V581_PDB_ADC ; B = P3V3_PDB_AUX_ADC_MAM
PC1320  Q_CAP  2.2UF 16V 20% X7R  pkg C0603  page 163 : A = P12V_OCP_AVIN_PD_2 ; B = GND

(kicad_pcb
	(version 20260206)
	(generator "pcbnew")
	(generator_version "10.0")
	(general
		(thickness 1.6)
		(legacy_teardrops no)
	)
	(paper "A4")
	(title_block
		(title "03242023_DA0F0TMBIJ0_F0T_Motherboard_J_brd_V01_OCP.brd")
		(comment 1 "Grand Teton / footprints 2563-2564 of 6105")
	)
	(layers
		(0 "F.Cu" signal "TOP")
		(4 "In1.Cu" signal "GND")
		(6 "In2.Cu" signal "IN1")
		(8 "In3.Cu" signal "GND1")
		(10 "In4.Cu" signal "IN2")
		(12 "In5.Cu" signal "GND2")
		(14 "In6.Cu" signal "IN3")
		(16 "In7.Cu" signal "GND3")
		(18 "In8.Cu" signal "VCC")
		(20 "In9.Cu" signal "VCC1")
		(22 "In10.Cu" signal "GND4")
		(24 "In11.Cu" signal "IN4")
		(26 "In12.Cu" signal "GND5")
		(28 "In13.Cu" signal "IN5")
		(30 "In14.Cu" signal "GND6")
		(32 "In15.Cu" signal "IN6")
		(34 "In16.Cu" signal "GND7")
		(2 "B.Cu" signal "BOTTOM")
		(9 "F.Adhes" user "F.Adhesive")
		(11 "B.Adhes" user "B.Adhesive")
		(13 "F.Paste" user "Package Geometry/Pastemask Top")
		(15 "B.Paste" user "Package Geometry/Pastemask Bottom")
		(5 "F.SilkS" user "Ref Des/Silkscreen Top")
		(7 "B.SilkS" user "Ref Des/Silkscreen Bottom")
		(1 "F.Mask" user "Board Geometry/Soldermask Top")
		(3 "B.Mask" user "Board Geometry/Soldermask Bottom")
		(17 "Dwgs.User" user "User.Drawings")
		(19 "Cmts.User" user "User.Comments")
		(21 "Eco1.User" user "User.Eco1")
		(23 "Eco2.User" user "User.Eco2")
		(25 "Edge.Cuts" user "Board Geometry/Outline")
		(27 "Margin" user)
		(31 "F.CrtYd" user "Package Geometry/Place Bound Top")
		(29 "B.CrtYd" user "Package Geometry/Place Bound Bottom")
		(35 "F.Fab" user "Ref Des/Assembly Top")
		(33 "B.Fab" user "Ref Des/Assembly Bottom")
	)
	(footprint ""
		(layer "F.Cu")
		(at 40.627554 -106.015282)
		(property "Reference" "R3687"
			(at 0 0 0)
			(layer "F.SilkS")
			(hide yes)
			(effects
				(font
					(size 1.27 1.27)
				)
			)
		)
		(property "Value" ""
			(at 0 0 0)
			(layer "F.Fab")
			(effects
				(font
					(size 1.27 1.27)
				)
			)
		)
		(duplicate_pad_numbers_are_jumpers no)
		(fp_line
			(start -0.7874 -0.4064)
			(end 0.7874 -0.4064)
			(stroke
				(width 0.1524)
				(type default)
			)
			(layer "F.SilkS")
		)
		(fp_line
			(start -0.7874 0.4064)
			(end -0.7874 -0.4064)
			(stroke
				(width 0.1524)
				(type default)
			)
			(layer "F.SilkS")
		)
		(fp_line
			(start 0.7874 -0.4064)
			(end 0.7874 0.4064)
			(stroke
				(width 0.1524)
				(type default)
			)
			(layer "F.SilkS")
		)
		(fp_line
			(start 0.7874 0.4064)
			(end -0.7874 0.4064)
			(stroke
				(width 0.1524)
				(type default)
			)
			(layer "F.SilkS")
		)
		(fp_line
			(start -0.67945 -0.305054)
			(end -0.12065 -0.305054)
			(stroke
				(width 0.1)
				(type default)
			)
			(layer "F.Fab")
		)
		(fp_line
			(start -0.67945 0.3048)
			(end -0.67945 -0.305054)
			(stroke
				(width 0.1)
				(type default)
			)
			(layer "F.Fab")
		)
		(fp_line
			(start -0.12065 -0.305054)
			(end -0.12065 -0.2794)
			(stroke
				(width 0.1)
				(type default)
			)
			(layer "F.Fab")
		)
		(fp_line
			(start -0.12065 -0.2794)
			(end 0.12065 -0.2794)
			(stroke
				(width 0.1)
				(type default)
			)
			(layer "F.Fab")
		)
		(fp_line
			(start -0.12065 0.2794)
			(end -0.12065 0.3048)
			(stroke
				(width 0.1)
				(type default)
			)
			(layer "F.Fab")
		)
		(fp_line
			(start -0.12065 0.3048)
			(end -0.67945 0.3048)
			(stroke
				(width 0.1)
				(type default)
			)
			(layer "F.Fab")
		)
		(fp_line
			(start 0.120396 0.2794)
			(end -0.12065 0.2794)
			(stroke
				(width 0.1)
				(type default)
			)
			(layer "F.Fab")
		)
		(fp_line
			(start 0.120396 0.3048)
			(end 0.120396 0.2794)
			(stroke
				(width 0.1)
				(type default)
			)
			(layer "F.Fab")
		)
		(fp_line
			(start 0.12065 -0.3048)
			(end 0.67945 -0.3048)
			(stroke
				(width 0.1)
				(type default)
			)
			(layer "F.Fab")
		)
		(fp_line
			(start 0.12065 -0.2794)
			(end 0.12065 -0.3048)
			(stroke
				(width 0.1)
				(type default)
			)
			(layer "F.Fab")
		)
		(fp_line
			(start 0.67945 -0.3048)
			(end 0.67945 0.3048)
			(stroke
				(width 0.1)
				(type default)
			)
			(layer "F.Fab")
		)
		(fp_line
			(start 0.67945 0.3048)
			(end 0.120396 0.3048)
			(stroke
				(width 0.1)
				(type default)
			)
			(layer "F.Fab")
		)
		(pad "1" smd rect
			(at -0.40005 0 180)
			(size 0.4572 0.508)
			(layers "F.Cu" "F.Mask" "F.Paste")
			(net "P1V581_PDB_ADC")
		)
		(pad "2" smd rect
			(at 0.40005 0 180)
			(size 0.4572 0.508)
			(layers "F.Cu" "F.Mask" "F.Paste")
			(net "P3V3_PDB_AUX_ADC_MAM")
		)
	)
	(footprint ""
		(layer "F.Cu")
		(at 64.614298 -24.798782 180)
		(property "Reference" "PC1320"
			(at 0 0 180)
			(layer "F.SilkS")
			(hide yes)
			(effects
				(font
					(size 1.27 1.27)
				)
			)
		)
		(property "Value" ""
			(at 0 0 180)
			(layer "F.Fab")
			(effects
				(font
					(size 1.27 1.27)
				)
			)
		)
		(duplicate_pad_numbers_are_jumpers no)
		(fp_line
			(start 1.2954 0.5842)
			(end -1.2954 0.5842)
			(stroke
				(width 0.1524)
				(type default)
			)
			(layer "F.SilkS")
		)
		(fp_line
			(start 1.2954 -0.5842)
			(end 1.2954 0.5842)
			(stroke
				(width 0.1524)
				(type default)
			)
			(layer "F.SilkS")
		)
		(fp_line
			(start 0 -0.5842)
			(end 0 0.5842)
			(stroke
				(width 0.1524)
				(type default)
			)
			(layer "F.SilkS")
		)
		(fp_line
			(start -1.2954 0.5842)
			(end -1.2954 -0.5842)
			(stroke
				(width 0.1524)
				(type default)
			)
			(layer "F.SilkS")
		)
		(fp_line
			(start -1.2954 -0.5842)
			(end 1.2954 -0.5842)
			(stroke
				(width 0.1524)
				(type default)
			)
			(layer "F.SilkS")
		)
		(fp_line
			(start 1.1938 0.4064)
			(end 0.8636 0.4064)
			(stroke
				(width 0.1)
				(type default)
			)
			(layer "F.Fab")
		)
		(fp_line
			(start 1.1938 -0.4064)
			(end 1.1938 0.4064)
			(stroke
				(width 0.1)
				(type default)
			)
			(layer "F.Fab")
		)
		(fp_line
			(start 0.8636 0.4572)
			(end -0.8636 0.4572)
			(stroke
				(width 0.1)
				(type default)
			)
			(layer "F.Fab")
		)
		(fp_line
			(start 0.8636 0.4064)
			(end 0.8636 0.4572)
			(stroke
				(width 0.1)
				(type default)
			)
			(layer "F.Fab")
		)
		(fp_line
			(start 0.8636 -0.4064)
			(end 1.1938 -0.4064)
			(stroke
				(width 0.1)
				(type default)
			)
			(layer "F.Fab")
		)
		(fp_line
			(start 0.8636 -0.4572)
			(end 0.8636 -0.4064)
			(stroke
				(width 0.1)
				(type default)
			)
			(layer "F.Fab")
		)
		(fp_line
			(start -0.8636 0.4572)
			(end -0.8636 0.4064)
			(stroke
				(width 0.1)
				(type default)
			)
			(layer "F.Fab")
		)
		(fp_line
			(start -0.8636 0.4064)
			(end -1.1938 0.4064)
			(stroke
				(width 0.1)
				(type default)
			)
			(layer "F.Fab")
		)
		(fp_line
			(start -0.8636 -0.4064)
			(end -0.8636 -0.4572)
			(stroke
				(width 0.1)
				(type default)
			)
			(layer "F.Fab")
		)
		(fp_line
			(start -0.8636 -0.4572)
			(end 0.8636 -0.4572)
			(stroke
				(width 0.1)
				(type default)
			)
			(layer "F.Fab")
		)
		(fp_line
			(start -1.1938 0.4064)
			(end -1.1938 -0.4064)
			(stroke
				(width 0.1)
				(type default)
			)
			(layer "F.Fab")
		)
		(fp_line
			(start -1.1938 -0.4064)
			(end -0.8636 -0.4064)
			(stroke
				(width 0.1)
				(type default)
			)
			(layer "F.Fab")
		)
		(pad "1" smd rect
			(at -0.7366 0 90)
			(size 0.7112 0.8128)
			(layers "F.Cu" "F.Mask" "F.Paste")
			(net "P12V_OCP_AVIN_PD_2")
		)
		(pad "2" smd rect
			(at 0.7366 0 90)
			(size 0.7112 0.8128)
			(layers "F.Cu" "F.Mask" "F.Paste")
			(net "GND")
		)
	)
)
